FILE_TYPE = CONNECTIVITY;
{Allegro Design Entry HDL 17.2-2016 S081 (4005846) 1/11/2022}
"PAGE_NUMBER" = 165;
0"NC";
1"P5E_CPU0_PE1_TX_DP<7:0>";
2"P5E_CPU0_PE1_TX_DN<7:0>";
3"P5E_CPU0_PE1_TX_C_DN<7:0>";
4"P5E_CPU0_PE1_TX_DN<15:8>";
5"P5E_CPU0_PE1_TX_DP<15:8>";
6"P5E_CPU0_PE1_TX_C_DN<15:8>";
7"P5E_CPU0_PE1_TX_C_DP<15:8>";
8"P5E_CPU0_PE1_TX_C_DP<7:0>";
9"P5E_CPU0_PE3_TX_DP<7:0>";
10"P5E_CPU0_PE3_TX_DN<7:0>";
11"P5E_CPU0_PE3_TX_DP<15:8>";
12"P5E_CPU0_PE3_TX_DN<15:8>";
13"P5E_CPU0_PE3_TX_C_DP<15:8>";
14"P5E_CPU0_PE3_TX_C_DN<15:8>";
15"P5E_CPU0_PE3_TX_C_DP<7:0>";
16"P5E_CPU0_PE3_TX_C_DN<7:0>";
17"P5E_CPU0_PE1_TX_C_DN<15>";
18"P5E_CPU0_PE1_TX_C_DP<15>";
19"P5E_CPU0_PE1_TX_C_DN<14>";
20"P5E_CPU0_PE1_TX_C_DP<14>";
21"P5E_CPU0_PE1_TX_C_DN<13>";
22"P5E_CPU0_PE1_TX_C_DP<13>";
23"P5E_CPU0_PE1_TX_DN<12>";
24"P5E_CPU0_PE1_TX_DP<12>";
25"P5E_CPU0_PE1_TX_C_DP<0>";
26"P5E_CPU0_PE1_TX_C_DP<6>";
27"P5E_CPU0_PE1_TX_C_DN<5>";
28"P5E_CPU0_PE3_TX_DP<4>";
29"P5E_CPU0_PE3_TX_DN<3>";
30"P5E_CPU0_PE3_TX_DN<2>";
31"P5E_CPU0_PE3_TX_C_DP<1>";
32"P5E_CPU0_PE3_TX_C_DP<0>";
33"P5E_CPU0_PE3_TX_C_DN<0>";
34"P5E_CPU0_PE3_TX_C_DP<14>";
35"P5E_CPU0_PE3_TX_C_DP<15>";
36"P5E_CPU0_PE3_TX_C_DN<15>";
37"P5E_CPU0_PE3_TX_C_DN<14>";
38"P5E_CPU0_PE3_TX_C_DP<11>";
39"P5E_CPU0_PE3_TX_C_DP<10>";
40"P5E_CPU0_PE3_TX_C_DP<9>";
41"P5E_CPU0_PE3_TX_C_DN<12>";
42"P5E_CPU0_PE3_TX_C_DN<11>";
43"P5E_CPU0_PE3_TX_C_DN<10>";
44"P5E_CPU0_PE3_TX_C_DN<8>";
45"P5E_CPU0_PE3_TX_C_DN<9>";
46"P5E_CPU0_PE3_TX_C_DP<7>";
47"P5E_CPU0_PE3_TX_C_DN<7>";
48"P5E_CPU0_PE3_TX_C_DN<6>";
49"P5E_CPU0_PE3_TX_C_DN<5>";
50"P5E_CPU0_PE3_TX_C_DN<4>";
51"P5E_CPU0_PE3_TX_C_DP<3>";
52"P5E_CPU0_PE3_TX_C_DP<2>";
53"P5E_CPU0_PE3_TX_C_DP<4>";
54"P5E_CPU0_PE3_TX_C_DN<3>";
55"P5E_CPU0_PE3_TX_C_DN<2>";
56"P5E_CPU0_PE3_TX_C_DN<1>";
57"P5E_CPU0_PE3_TX_C_DP<8>";
58"P5E_CPU0_PE3_TX_C_DP<6>";
59"P5E_CPU0_PE3_TX_C_DP<5>";
60"P5E_CPU0_PE3_TX_C_DN<13>";
61"P5E_CPU0_PE3_TX_C_DP<13>";
62"P5E_CPU0_PE3_TX_C_DP<12>";
63"P5E_CPU0_PE3_TX_DN<14>";
64"P5E_CPU0_PE3_TX_DN<13>";
65"P5E_CPU0_PE3_TX_DN<15>";
66"P5E_CPU0_PE3_TX_DN<8>";
67"P5E_CPU0_PE3_TX_DN<11>";
68"P5E_CPU0_PE3_TX_DN<9>";
69"P5E_CPU0_PE3_TX_DN<10>";
70"P5E_CPU0_PE3_TX_DN<12>";
71"P5E_CPU0_PE3_TX_DP<14>";
72"P5E_CPU0_PE3_TX_DP<15>";
73"P5E_CPU0_PE3_TX_DP<13>";
74"P5E_CPU0_PE3_TX_DP<8>";
75"P5E_CPU0_PE3_TX_DP<11>";
76"P5E_CPU0_PE3_TX_DP<10>";
77"P5E_CPU0_PE3_TX_DP<9>";
78"P5E_CPU0_PE3_TX_DP<12>";
79"P5E_CPU0_PE3_TX_DN<7>";
80"P5E_CPU0_PE3_TX_DN<6>";
81"P5E_CPU0_PE3_TX_DN<5>";
82"P5E_CPU0_PE3_TX_DN<4>";
83"P5E_CPU0_PE3_TX_DN<0>";
84"P5E_CPU0_PE3_TX_DN<1>";
85"P5E_CPU0_PE3_TX_DP<7>";
86"P5E_CPU0_PE3_TX_DP<6>";
87"P5E_CPU0_PE3_TX_DP<2>";
88"P5E_CPU0_PE3_TX_DP<1>";
89"P5E_CPU0_PE3_TX_DP<3>";
90"P5E_CPU0_PE3_TX_DP<5>";
91"P5E_CPU0_PE3_TX_DP<0>";
92"P5E_CPU0_PE1_TX_C_DP<5>";
93"P5E_CPU0_PE1_TX_C_DP<7>";
94"P5E_CPU0_PE1_TX_C_DP<1>";
95"P5E_CPU0_PE1_TX_C_DP<4>";
96"P5E_CPU0_PE1_TX_C_DP<3>";
97"P5E_CPU0_PE1_TX_C_DP<2>";
98"P5E_CPU0_PE1_TX_C_DP<8>";
99"P5E_CPU0_PE1_TX_C_DP<12>";
100"P5E_CPU0_PE1_TX_C_DP<11>";
101"P5E_CPU0_PE1_TX_C_DP<10>";
102"P5E_CPU0_PE1_TX_C_DP<9>";
103"P5E_CPU0_PE1_TX_C_DN<12>";
104"P5E_CPU0_PE1_TX_C_DN<11>";
105"P5E_CPU0_PE1_TX_C_DN<10>";
106"P5E_CPU0_PE1_TX_C_DN<8>";
107"P5E_CPU0_PE1_TX_C_DN<9>";
108"P5E_CPU0_PE1_TX_DP<13>";
109"P5E_CPU0_PE1_TX_DN<11>";
110"P5E_CPU0_PE1_TX_DP<11>";
111"P5E_CPU0_PE1_TX_DP<10>";
112"P5E_CPU0_PE1_TX_DP<9>";
113"P5E_CPU0_PE1_TX_DP<8>";
114"P5E_CPU0_PE1_TX_DP<14>";
115"P5E_CPU0_PE1_TX_DN<14>";
116"P5E_CPU0_PE1_TX_DP<15>";
117"P5E_CPU0_PE1_TX_DN<13>";
118"P5E_CPU0_PE1_TX_DN<9>";
119"P5E_CPU0_PE1_TX_DN<10>";
120"P5E_CPU0_PE1_TX_DN<8>";
121"P5E_CPU0_PE1_TX_DN<15>";
122"P5E_CPU0_PE1_TX_C_DN<7>";
123"P5E_CPU0_PE1_TX_C_DN<6>";
124"P5E_CPU0_PE1_TX_C_DN<2>";
125"P5E_CPU0_PE1_TX_C_DN<4>";
126"P5E_CPU0_PE1_TX_C_DN<3>";
127"P5E_CPU0_PE1_TX_C_DN<1>";
128"P5E_CPU0_PE1_TX_C_DN<0>";
129"P5E_CPU0_PE1_TX_DN<1>";
130"P5E_CPU0_PE1_TX_DP<3>";
131"P5E_CPU0_PE1_TX_DP<4>";
132"P5E_CPU0_PE1_TX_DN<7>";
133"P5E_CPU0_PE1_TX_DN<5>";
134"P5E_CPU0_PE1_TX_DP<6>";
135"P5E_CPU0_PE1_TX_DN<3>";
136"P5E_CPU0_PE1_TX_DN<0>";
137"P5E_CPU0_PE1_TX_DP<7>";
138"P5E_CPU0_PE1_TX_DN<6>";
139"P5E_CPU0_PE1_TX_DP<0>";
140"P5E_CPU0_PE1_TX_DP<1>";
141"P5E_CPU0_PE1_TX_DP<2>";
142"P5E_CPU0_PE1_TX_DN<2>";
143"P5E_CPU0_PE1_TX_DN<4>";
144"P5E_CPU0_PE1_TX_DP<5>";
%"TAP"
"1","(-1375,175)","2","standard","I10";
;
CDS_LIB"standard"
BODY_TYPE"PLUMBING"
HDL_TAP"TRUE";
"B \NAC \NWC"2;
"S \NAC"
BN"0"136;
%"TAP"
"1","(100,2700)","0","standard","I100";
;
CDS_LIB"standard"
BODY_TYPE"PLUMBING"
HDL_TAP"TRUE";
"B \NAC \NWC"7;
"S \NAC"
BN"11"100;
%"TAP"
"1","(100,2900)","0","standard","I101";
;
CDS_LIB"standard"
BODY_TYPE"PLUMBING"
HDL_TAP"TRUE";
"B \NAC \NWC"7;
"S \NAC"
BN"12"99;
%"TAP"
"1","(100,3100)","0","standard","I102";
;
CDS_LIB"standard"
BODY_TYPE"PLUMBING"
HDL_TAP"TRUE";
"B \NAC \NWC"7;
"S \NAC"
BN"13"22;
%"TAP"
"1","(100,3300)","0","standard","I103";
;
CDS_LIB"standard"
BODY_TYPE"PLUMBING"
HDL_TAP"TRUE";
"B \NAC \NWC"7;
"S \NAC"
BN"14"20;
%"TAP"
"1","(100,3500)","0","standard","I104";
;
CDS_LIB"standard"
BODY_TYPE"PLUMBING"
HDL_TAP"TRUE";
"B \NAC \NWC"7;
"S \NAC"
BN"15"18;
%"TAP"
"1","(2850,125)","2","standard","I109";
;
CDS_LIB"standard"
BODY_TYPE"PLUMBING"
HDL_TAP"TRUE";
"B \NAC \NWC"9;
"S \NAC"
BN"0"91;
%"TAP"
"1","(-1375,375)","2","standard","I11";
;
CDS_LIB"standard"
BODY_TYPE"PLUMBING"
HDL_TAP"TRUE";
"B \NAC \NWC"2;
"S \NAC"
BN"1"129;
%"TAP"
"1","(2850,325)","2","standard","I110";
;
CDS_LIB"standard"
BODY_TYPE"PLUMBING"
HDL_TAP"TRUE";
"B \NAC \NWC"9;
"S \NAC"
BN"1"88;
%"TAP"
"1","(2850,525)","2","standard","I111";
;
CDS_LIB"standard"
BODY_TYPE"PLUMBING"
HDL_TAP"TRUE";
"B \NAC \NWC"9;
"S \NAC"
BN"2"87;
%"TAP"
"1","(2850,725)","2","standard","I112";
;
CDS_LIB"standard"
BODY_TYPE"PLUMBING"
HDL_TAP"TRUE";
"B \NAC \NWC"9;
"S \NAC"
BN"3"89;
%"TAP"
"1","(2850,925)","2","standard","I113";
;
CDS_LIB"standard"
BODY_TYPE"PLUMBING"
HDL_TAP"TRUE";
"B \NAC \NWC"9;
"S \NAC"
BN"4"28;
%"TAP"
"1","(2850,1325)","2","standard","I114";
;
CDS_LIB"standard"
BODY_TYPE"PLUMBING"
HDL_TAP"TRUE";
"B \NAC \NWC"9;
"S \NAC"
BN"6"86;
%"TAP"
"1","(2850,1525)","2","standard","I115";
;
CDS_LIB"standard"
BODY_TYPE"PLUMBING"
HDL_TAP"TRUE";
"B \NAC \NWC"9;
"S \NAC"
BN"7"85;
%"TAP"
"1","(3100,175)","2","standard","I116";
;
CDS_LIB"standard"
BODY_TYPE"PLUMBING"
HDL_TAP"TRUE";
"B \NAC \NWC"10;
"S \NAC"
BN"0"83;
%"TAP"
"1","(3100,375)","2","standard","I117";
;
CDS_LIB"standard"
BODY_TYPE"PLUMBING"
HDL_TAP"TRUE";
"B \NAC \NWC"10;
"S \NAC"
BN"1"84;
%"TAP"
"1","(3100,575)","2","standard","I118";
;
CDS_LIB"standard"
BODY_TYPE"PLUMBING"
HDL_TAP"TRUE";
"B \NAC \NWC"10;
"S \NAC"
BN"2"30;
%"TAP"
"1","(3100,775)","2","standard","I119";
;
CDS_LIB"standard"
BODY_TYPE"PLUMBING"
HDL_TAP"TRUE";
"B \NAC \NWC"10;
"S \NAC"
BN"3"29;
%"TAP"
"1","(-1375,575)","2","standard","I12";
;
CDS_LIB"standard"
BODY_TYPE"PLUMBING"
HDL_TAP"TRUE";
"B \NAC \NWC"2;
"S \NAC"
BN"2"142;
%"Q_CAP_DIFFBUS"
"2","(3825,125)","2","pure_quanta","I120";
;
PART_NUMBER"SP_CH4221MEE01"
VALUE"DIFF BUS_0.22UF"
$LOCATION"C901"
PIN_NAMES_ROTATE"TRUE"
CDS_LIB"pure_quanta"
CDS_LMAN_SYM_OUTLINE"-25,50,25,-50"
VOLTAGE"6.3V"
MATERIAL"X6S"
PACK_TYPE"C0201"
TOLERANCE"20%"
$LOCATION"C901"
CDS_LOCATION"C901"
$SEC"1"
CDS_SEC"1";
"2"
$PN"2"91;
"1"
$PN"1"32;
%"Q_CAP_DIFFBUS"
"2","(3825,175)","2","pure_quanta","I121";
;
PART_NUMBER"SP_CH4221MEE01"
VALUE"DIFF BUS_0.22UF"
$LOCATION"C900"
PIN_NAMES_ROTATE"TRUE"
CDS_LIB"pure_quanta"
CDS_LMAN_SYM_OUTLINE"-25,50,25,-50"
VOLTAGE"6.3V"
MATERIAL"X6S"
PACK_TYPE"C0201"
TOLERANCE"20%"
$LOCATION"C900"
CDS_LOCATION"C900"
$SEC"1"
CDS_SEC"1";
"2"
$PN"2"83;
"1"
$PN"1"33;
%"Q_CAP_DIFFBUS"
"2","(3825,325)","2","pure_quanta","I122";
;
PART_NUMBER"SP_CH4221MEE01"
VALUE"DIFF BUS_0.22UF"
$LOCATION"C899"
PIN_NAMES_ROTATE"TRUE"
CDS_LIB"pure_quanta"
CDS_LMAN_SYM_OUTLINE"-25,50,25,-50"
VOLTAGE"6.3V"
MATERIAL"X6S"
PACK_TYPE"C0201"
TOLERANCE"20%"
$LOCATION"C899"
CDS_LOCATION"C899"
$SEC"1"
CDS_SEC"1";
"2"
$PN"2"88;
"1"
$PN"1"31;
%"Q_CAP_DIFFBUS"
"2","(3825,525)","2","pure_quanta","I123";
;
PART_NUMBER"SP_CH4221MEE01"
VALUE"DIFF BUS_0.22UF"
$LOCATION"C897"
PIN_NAMES_ROTATE"TRUE"
CDS_LIB"pure_quanta"
CDS_LMAN_SYM_OUTLINE"-25,50,25,-50"
VOLTAGE"6.3V"
MATERIAL"X6S"
PACK_TYPE"C0201"
TOLERANCE"20%"
$LOCATION"C897"
CDS_LOCATION"C897"
$SEC"1"
CDS_SEC"1";
"2"
$PN"2"87;
"1"
$PN"1"52;
%"Q_CAP_DIFFBUS"
"2","(3825,575)","2","pure_quanta","I124";
;
PART_NUMBER"SP_CH4221MEE01"
VALUE"DIFF BUS_0.22UF"
$LOCATION"C896"
PIN_NAMES_ROTATE"TRUE"
CDS_LIB"pure_quanta"
CDS_LMAN_SYM_OUTLINE"-25,50,25,-50"
VOLTAGE"6.3V"
MATERIAL"X6S"
PACK_TYPE"C0201"
TOLERANCE"20%"
$LOCATION"C896"
CDS_LOCATION"C896"
$SEC"1"
CDS_SEC"1";
"2"
$PN"2"30;
"1"
$PN"1"55;
%"Q_CAP_DIFFBUS"
"2","(3825,725)","2","pure_quanta","I125";
;
PART_NUMBER"SP_CH4221MEE01"
VALUE"DIFF BUS_0.22UF"
$LOCATION"C895"
PIN_NAMES_ROTATE"TRUE"
CDS_LMAN_SYM_OUTLINE"-25,50,25,-50"
CDS_LIB"pure_quanta"
VOLTAGE"6.3V"
MATERIAL"X6S"
PACK_TYPE"C0201"
TOLERANCE"20%"
$LOCATION"C895"
CDS_LOCATION"C895"
$SEC"1"
CDS_SEC"1";
"2"
$PN"2"89;
"1"
$PN"1"51;
%"Q_CAP_DIFFBUS"
"2","(3825,775)","2","pure_quanta","I126";
;
PART_NUMBER"SP_CH4221MEE01"
VALUE"DIFF BUS_0.22UF"
$LOCATION"C894"
PIN_NAMES_ROTATE"TRUE"
CDS_LMAN_SYM_OUTLINE"-25,50,25,-50"
CDS_LIB"pure_quanta"
VOLTAGE"6.3V"
MATERIAL"X6S"
PACK_TYPE"C0201"
TOLERANCE"20%"
$LOCATION"C894"
CDS_LOCATION"C894"
$SEC"1"
CDS_SEC"1";
"2"
$PN"2"29;
"1"
$PN"1"54;
%"Q_CAP_DIFFBUS"
"2","(3825,975)","2","pure_quanta","I127";
;
PART_NUMBER"SP_CH4221MEE01"
VALUE"DIFF BUS_0.22UF"
$LOCATION"C892"
PIN_NAMES_ROTATE"TRUE"
CDS_LIB"pure_quanta"
CDS_LMAN_SYM_OUTLINE"-25,50,25,-50"
VOLTAGE"6.3V"
MATERIAL"X6S"
PACK_TYPE"C0201"
TOLERANCE"20%"
$LOCATION"C892"
CDS_LOCATION"C892"
$SEC"1"
CDS_SEC"1";
"2"
$PN"2"82;
"1"
$PN"1"50;
%"Q_CAP_DIFFBUS"
"2","(3825,925)","2","pure_quanta","I128";
;
PART_NUMBER"SP_CH4221MEE01"
VALUE"DIFF BUS_0.22UF"
$LOCATION"C893"
PIN_NAMES_ROTATE"TRUE"
CDS_LIB"pure_quanta"
CDS_LMAN_SYM_OUTLINE"-25,50,25,-50"
VOLTAGE"6.3V"
MATERIAL"X6S"
PACK_TYPE"C0201"
TOLERANCE"20%"
$LOCATION"C893"
CDS_LOCATION"C893"
$SEC"1"
CDS_SEC"1";
"2"
$PN"2"28;
"1"
$PN"1"53;
%"TAP"
"1","(3100,1175)","2","standard","I129";
;
CDS_LIB"standard"
BODY_TYPE"PLUMBING"
HDL_TAP"TRUE";
"B \NAC \NWC"10;
"S \NAC"
BN"5"81;
%"TAP"
"1","(-1375,775)","2","standard","I13";
;
CDS_LIB"standard"
BODY_TYPE"PLUMBING"
HDL_TAP"TRUE";
"B \NAC \NWC"2;
"S \NAC"
BN"3"135;
%"TAP"
"1","(3100,1375)","2","standard","I130";
;
CDS_LIB"standard"
BODY_TYPE"PLUMBING"
HDL_TAP"TRUE";
"B \NAC \NWC"10;
"S \NAC"
BN"6"80;
%"TAP"
"1","(3100,1575)","2","standard","I131";
;
CDS_LIB"standard"
BODY_TYPE"PLUMBING"
HDL_TAP"TRUE";
"B \NAC \NWC"10;
"S \NAC"
BN"7"79;
%"Q_CAP_DIFFBUS"
"2","(3825,1125)","2","pure_quanta","I132";
;
PART_NUMBER"SP_CH4221MEE01"
VALUE"DIFF BUS_0.22UF"
$LOCATION"C891"
PIN_NAMES_ROTATE"TRUE"
CDS_LIB"pure_quanta"
CDS_LMAN_SYM_OUTLINE"-25,50,25,-50"
VOLTAGE"6.3V"
MATERIAL"X6S"
PACK_TYPE"C0201"
TOLERANCE"20%"
$LOCATION"C891"
CDS_LOCATION"C891"
$SEC"1"
CDS_SEC"1";
"2"
$PN"2"90;
"1"
$PN"1"59;
%"Q_CAP_DIFFBUS"
"2","(3825,1175)","2","pure_quanta","I133";
;
PART_NUMBER"SP_CH4221MEE01"
VALUE"DIFF BUS_0.22UF"
$LOCATION"C890"
PIN_NAMES_ROTATE"TRUE"
CDS_LIB"pure_quanta"
CDS_LMAN_SYM_OUTLINE"-25,50,25,-50"
VOLTAGE"6.3V"
MATERIAL"X6S"
PACK_TYPE"C0201"
TOLERANCE"20%"
$LOCATION"C890"
CDS_LOCATION"C890"
$SEC"1"
CDS_SEC"1";
"2"
$PN"2"81;
"1"
$PN"1"49;
%"Q_CAP_DIFFBUS"
"2","(3825,1325)","2","pure_quanta","I134";
;
PART_NUMBER"SP_CH4221MEE01"
VALUE"DIFF BUS_0.22UF"
$LOCATION"C889"
PIN_NAMES_ROTATE"TRUE"
CDS_LIB"pure_quanta"
CDS_LMAN_SYM_OUTLINE"-25,50,25,-50"
VOLTAGE"6.3V"
MATERIAL"X6S"
PACK_TYPE"C0201"
TOLERANCE"20%"
$LOCATION"C889"
CDS_LOCATION"C889"
$SEC"1"
CDS_SEC"1";
"2"
$PN"2"86;
"1"
$PN"1"58;
%"Q_CAP_DIFFBUS"
"2","(3825,1375)","2","pure_quanta","I135";
;
PART_NUMBER"SP_CH4221MEE01"
VALUE"DIFF BUS_0.22UF"
$LOCATION"C888"
PIN_NAMES_ROTATE"TRUE"
CDS_LIB"pure_quanta"
CDS_LMAN_SYM_OUTLINE"-25,50,25,-50"
VOLTAGE"6.3V"
MATERIAL"X6S"
PACK_TYPE"C0201"
TOLERANCE"20%"
$LOCATION"C888"
CDS_LOCATION"C888"
$SEC"1"
CDS_SEC"1";
"2"
$PN"2"80;
"1"
$PN"1"48;
%"Q_CAP_DIFFBUS"
"2","(3825,1525)","2","pure_quanta","I136";
;
PART_NUMBER"SP_CH4221MEE01"
VALUE"DIFF BUS_0.22UF"
$LOCATION"C887"
PIN_NAMES_ROTATE"TRUE"
CDS_LIB"pure_quanta"
CDS_LMAN_SYM_OUTLINE"-25,50,25,-50"
VOLTAGE"6.3V"
MATERIAL"X6S"
PACK_TYPE"C0201"
TOLERANCE"20%"
$LOCATION"C887"
CDS_LOCATION"C887"
$SEC"1"
CDS_SEC"1";
"2"
$PN"2"85;
"1"
$PN"1"46;
%"Q_CAP_DIFFBUS"
"2","(3825,1575)","2","pure_quanta","I137";
;
PART_NUMBER"SP_CH4221MEE01"
VALUE"DIFF BUS_0.22UF"
$LOCATION"C886"
PIN_NAMES_ROTATE"TRUE"
CDS_LMAN_SYM_OUTLINE"-25,50,25,-50"
CDS_LIB"pure_quanta"
VOLTAGE"6.3V"
MATERIAL"X6S"
PACK_TYPE"C0201"
TOLERANCE"20%"
$LOCATION"C886"
CDS_LOCATION"C886"
$SEC"1"
CDS_SEC"1";
"2"
$PN"2"79;
"1"
$PN"1"47;
%"TAP"
"1","(2850,2100)","2","standard","I138";
;
CDS_LIB"standard"
BODY_TYPE"PLUMBING"
HDL_TAP"TRUE";
"B \NAC \NWC"11;
"S \NAC"
BN"8"74;
%"TAP"
"1","(2850,2300)","2","standard","I139";
;
CDS_LIB"standard"
BODY_TYPE"PLUMBING"
HDL_TAP"TRUE";
"B \NAC \NWC"11;
"S \NAC"
BN"9"77;
%"TAP"
"1","(-1375,975)","2","standard","I14";
;
CDS_LIB"standard"
BODY_TYPE"PLUMBING"
HDL_TAP"TRUE";
"B \NAC \NWC"2;
"S \NAC"
BN"4"143;
%"TAP"
"1","(2850,2500)","2","standard","I140";
;
CDS_LIB"standard"
BODY_TYPE"PLUMBING"
HDL_TAP"TRUE";
"B \NAC \NWC"11;
"S \NAC"
BN"10"76;
%"TAP"
"1","(2850,2700)","2","standard","I141";
;
CDS_LIB"standard"
BODY_TYPE"PLUMBING"
HDL_TAP"TRUE";
"B \NAC \NWC"11;
"S \NAC"
BN"11"75;
%"TAP"
"1","(2850,2900)","2","standard","I142";
;
CDS_LIB"standard"
BODY_TYPE"PLUMBING"
HDL_TAP"TRUE";
"B \NAC \NWC"11;
"S \NAC"
BN"12"78;
%"TAP"
"1","(2850,3100)","2","standard","I143";
;
CDS_LIB"standard"
BODY_TYPE"PLUMBING"
HDL_TAP"TRUE";
"B \NAC \NWC"11;
"S \NAC"
BN"13"73;
%"TAP"
"1","(2850,3300)","2","standard","I144";
;
CDS_LIB"standard"
BODY_TYPE"PLUMBING"
HDL_TAP"TRUE";
"B \NAC \NWC"11;
"S \NAC"
BN"14"71;
%"TAP"
"1","(2850,3500)","2","standard","I145";
;
CDS_LIB"standard"
BODY_TYPE"PLUMBING"
HDL_TAP"TRUE";
"B \NAC \NWC"11;
"S \NAC"
BN"15"72;
%"TAP"
"1","(3100,2150)","2","standard","I146";
;
CDS_LIB"standard"
BODY_TYPE"PLUMBING"
HDL_TAP"TRUE";
"B \NAC \NWC"12;
"S \NAC"
BN"8"66;
%"TAP"
"1","(3100,2350)","2","standard","I147";
;
CDS_LIB"standard"
BODY_TYPE"PLUMBING"
HDL_TAP"TRUE";
"B \NAC \NWC"12;
"S \NAC"
BN"9"68;
%"TAP"
"1","(3100,2550)","2","standard","I148";
;
CDS_LIB"standard"
BODY_TYPE"PLUMBING"
HDL_TAP"TRUE";
"B \NAC \NWC"12;
"S \NAC"
BN"10"69;
%"TAP"
"1","(3100,2750)","2","standard","I149";
;
CDS_LIB"standard"
BODY_TYPE"PLUMBING"
HDL_TAP"TRUE";
"B \NAC \NWC"12;
"S \NAC"
BN"11"67;
%"TAP"
"1","(-1625,1125)","2","standard","I15";
;
CDS_LIB"standard"
BODY_TYPE"PLUMBING"
HDL_TAP"TRUE";
"B \NAC \NWC"1;
"S \NAC"
BN"5"144;
%"TAP"
"1","(3100,2950)","2","standard","I150";
;
CDS_LIB"standard"
BODY_TYPE"PLUMBING"
HDL_TAP"TRUE";
"B \NAC \NWC"12;
"S \NAC"
BN"12"70;
%"Q_CAP_DIFFBUS"
"2","(3825,2150)","2","pure_quanta","I151";
;
PART_NUMBER"SP_CH4221MEE01"
VALUE"DIFF BUS_0.22UF"
$LOCATION"C884"
CDS_LMAN_SYM_OUTLINE"-25,50,25,-50"
CDS_LIB"pure_quanta"
PIN_NAMES_ROTATE"TRUE"
VOLTAGE"6.3V"
MATERIAL"X6S"
PACK_TYPE"C0201"
TOLERANCE"20%"
$LOCATION"C884"
CDS_LOCATION"C884"
$SEC"1"
CDS_SEC"1";
"2"
$PN"2"66;
"1"
$PN"1"44;
%"Q_CAP_DIFFBUS"
"2","(3825,2100)","2","pure_quanta","I152";
;
PART_NUMBER"SP_CH4221MEE01"
VALUE"DIFF BUS_0.22UF"
$LOCATION"C885"
CDS_LMAN_SYM_OUTLINE"-25,50,25,-50"
CDS_LIB"pure_quanta"
PIN_NAMES_ROTATE"TRUE"
VOLTAGE"6.3V"
MATERIAL"X6S"
PACK_TYPE"C0201"
TOLERANCE"20%"
$LOCATION"C885"
CDS_LOCATION"C885"
$SEC"1"
CDS_SEC"1";
"2"
$PN"2"74;
"1"
$PN"1"57;
%"Q_CAP_DIFFBUS"
"2","(3825,2300)","2","pure_quanta","I153";
;
PART_NUMBER"SP_CH4221MEE01"
VALUE"DIFF BUS_0.22UF"
$LOCATION"C883"
CDS_LMAN_SYM_OUTLINE"-25,50,25,-50"
CDS_LIB"pure_quanta"
PIN_NAMES_ROTATE"TRUE"
VOLTAGE"6.3V"
MATERIAL"X6S"
PACK_TYPE"C0201"
TOLERANCE"20%"
$LOCATION"C883"
CDS_LOCATION"C883"
$SEC"1"
CDS_SEC"1";
"2"
$PN"2"77;
"1"
$PN"1"40;
%"Q_CAP_DIFFBUS"
"2","(3825,2350)","2","pure_quanta","I154";
;
PART_NUMBER"SP_CH4221MEE01"
VALUE"DIFF BUS_0.22UF"
$LOCATION"C882"
CDS_LIB"pure_quanta"
CDS_LMAN_SYM_OUTLINE"-25,50,25,-50"
PIN_NAMES_ROTATE"TRUE"
VOLTAGE"6.3V"
MATERIAL"X6S"
PACK_TYPE"C0201"
TOLERANCE"20%"
$LOCATION"C882"
CDS_LOCATION"C882"
$SEC"1"
CDS_SEC"1";
"2"
$PN"2"68;
"1"
$PN"1"45;
%"Q_CAP_DIFFBUS"
"2","(3825,2500)","2","pure_quanta","I155";
;
PART_NUMBER"SP_CH4221MEE01"
VALUE"DIFF BUS_0.22UF"
$LOCATION"C881"
CDS_LMAN_SYM_OUTLINE"-25,50,25,-50"
CDS_LIB"pure_quanta"
PIN_NAMES_ROTATE"TRUE"
VOLTAGE"6.3V"
MATERIAL"X6S"
PACK_TYPE"C0201"
TOLERANCE"20%"
$LOCATION"C881"
CDS_LOCATION"C881"
$SEC"1"
CDS_SEC"1";
"2"
$PN"2"76;
"1"
$PN"1"39;
%"Q_CAP_DIFFBUS"
"2","(3825,2550)","2","pure_quanta","I156";
;
PART_NUMBER"SP_CH4221MEE01"
VALUE"DIFF BUS_0.22UF"
$LOCATION"C880"
CDS_LMAN_SYM_OUTLINE"-25,50,25,-50"
CDS_LIB"pure_quanta"
PIN_NAMES_ROTATE"TRUE"
VOLTAGE"6.3V"
MATERIAL"X6S"
PACK_TYPE"C0201"
TOLERANCE"20%"
$LOCATION"C880"
CDS_LOCATION"C880"
$SEC"1"
CDS_SEC"1";
"2"
$PN"2"69;
"1"
$PN"1"43;
%"Q_CAP_DIFFBUS"
"2","(3825,2750)","2","pure_quanta","I157";
;
PART_NUMBER"SP_CH4221MEE01"
VALUE"DIFF BUS_0.22UF"
$LOCATION"C878"
CDS_LIB"pure_quanta"
CDS_LMAN_SYM_OUTLINE"-25,50,25,-50"
PIN_NAMES_ROTATE"TRUE"
VOLTAGE"6.3V"
MATERIAL"X6S"
PACK_TYPE"C0201"
TOLERANCE"20%"
$LOCATION"C878"
CDS_LOCATION"C878"
$SEC"1"
CDS_SEC"1";
"2"
$PN"2"67;
"1"
$PN"1"42;
%"Q_CAP_DIFFBUS"
"2","(3825,2700)","2","pure_quanta","I158";
;
PART_NUMBER"SP_CH4221MEE01"
VALUE"DIFF BUS_0.22UF"
$LOCATION"C879"
CDS_LIB"pure_quanta"
CDS_LMAN_SYM_OUTLINE"-25,50,25,-50"
PIN_NAMES_ROTATE"TRUE"
VOLTAGE"6.3V"
MATERIAL"X6S"
PACK_TYPE"C0201"
TOLERANCE"20%"
$LOCATION"C879"
CDS_LOCATION"C879"
$SEC"1"
CDS_SEC"1";
"2"
$PN"2"75;
"1"
$PN"1"38;
%"Q_CAP_DIFFBUS"
"2","(3825,2900)","2","pure_quanta","I159";
;
PART_NUMBER"SP_CH4221MEE01"
VALUE"DIFF BUS_0.22UF"
$LOCATION"C877"
CDS_LMAN_SYM_OUTLINE"-25,50,25,-50"
CDS_LIB"pure_quanta"
PIN_NAMES_ROTATE"TRUE"
VOLTAGE"6.3V"
MATERIAL"X6S"
PACK_TYPE"C0201"
TOLERANCE"20%"
$LOCATION"C877"
CDS_LOCATION"C877"
$SEC"1"
CDS_SEC"1";
"2"
$PN"2"78;
"1"
$PN"1"62;
%"TAP"
"1","(-1625,1325)","2","standard","I16";
;
CDS_LIB"standard"
BODY_TYPE"PLUMBING"
HDL_TAP"TRUE";
"B \NAC \NWC"1;
"S \NAC"
BN"6"134;
%"Q_CAP_DIFFBUS"
"2","(3825,2950)","2","pure_quanta","I160";
;
PART_NUMBER"SP_CH4221MEE01"
VALUE"DIFF BUS_0.22UF"
$LOCATION"C876"
CDS_LMAN_SYM_OUTLINE"-25,50,25,-50"
CDS_LIB"pure_quanta"
PIN_NAMES_ROTATE"TRUE"
VOLTAGE"6.3V"
MATERIAL"X6S"
PACK_TYPE"C0201"
TOLERANCE"20%"
$LOCATION"C876"
CDS_LOCATION"C876"
$SEC"1"
CDS_SEC"1";
"2"
$PN"2"70;
"1"
$PN"1"41;
%"TAP"
"1","(3100,3150)","2","standard","I161";
;
CDS_LIB"standard"
BODY_TYPE"PLUMBING"
HDL_TAP"TRUE";
"B \NAC \NWC"12;
"S \NAC"
BN"13"64;
%"TAP"
"1","(3100,3350)","2","standard","I162";
;
CDS_LIB"standard"
BODY_TYPE"PLUMBING"
HDL_TAP"TRUE";
"B \NAC \NWC"12;
"S \NAC"
BN"14"63;
%"TAP"
"1","(3100,3550)","2","standard","I163";
;
CDS_LIB"standard"
BODY_TYPE"PLUMBING"
HDL_TAP"TRUE";
"B \NAC \NWC"12;
"S \NAC"
BN"15"65;
%"Q_CAP_DIFFBUS"
"2","(3825,3100)","2","pure_quanta","I164";
;
PART_NUMBER"SP_CH4221MEE01"
VALUE"DIFF BUS_0.22UF"
$LOCATION"C875"
CDS_LMAN_SYM_OUTLINE"-25,50,25,-50"
CDS_LIB"pure_quanta"
PIN_NAMES_ROTATE"TRUE"
VOLTAGE"6.3V"
MATERIAL"X6S"
PACK_TYPE"C0201"
TOLERANCE"20%"
$LOCATION"C875"
CDS_LOCATION"C875"
$SEC"1"
CDS_SEC"1";
"2"
$PN"2"73;
"1"
$PN"1"61;
%"Q_CAP_DIFFBUS"
"2","(3825,3150)","2","pure_quanta","I165";
;
PART_NUMBER"SP_CH4221MEE01"
VALUE"DIFF BUS_0.22UF"
$LOCATION"C874"
CDS_LMAN_SYM_OUTLINE"-25,50,25,-50"
CDS_LIB"pure_quanta"
PIN_NAMES_ROTATE"TRUE"
VOLTAGE"6.3V"
MATERIAL"X6S"
PACK_TYPE"C0201"
TOLERANCE"20%"
$LOCATION"C874"
CDS_LOCATION"C874"
$SEC"1"
CDS_SEC"1";
"2"
$PN"2"64;
"1"
$PN"1"60;
%"Q_CAP_DIFFBUS"
"2","(3825,3300)","2","pure_quanta","I166";
;
PART_NUMBER"SP_CH4221MEE01"
VALUE"DIFF BUS_0.22UF"
$LOCATION"C873"
CDS_LMAN_SYM_OUTLINE"-25,50,25,-50"
CDS_LIB"pure_quanta"
PIN_NAMES_ROTATE"TRUE"
VOLTAGE"6.3V"
MATERIAL"X6S"
PACK_TYPE"C0201"
TOLERANCE"20%"
$LOCATION"C873"
CDS_LOCATION"C873"
$SEC"1"
CDS_SEC"1";
"2"
$PN"2"71;
"1"
$PN"1"34;
%"Q_CAP_DIFFBUS"
"2","(3825,3350)","2","pure_quanta","I167";
;
PART_NUMBER"SP_CH4221MEE01"
VALUE"DIFF BUS_0.22UF"
$LOCATION"C872"
CDS_LMAN_SYM_OUTLINE"-25,50,25,-50"
CDS_LIB"pure_quanta"
PIN_NAMES_ROTATE"TRUE"
VOLTAGE"6.3V"
MATERIAL"X6S"
PACK_TYPE"C0201"
TOLERANCE"20%"
$LOCATION"C872"
CDS_LOCATION"C872"
$SEC"1"
CDS_SEC"1";
"2"
$PN"2"63;
"1"
$PN"1"37;
%"Q_CAP_DIFFBUS"
"2","(3825,3500)","2","pure_quanta","I168";
;
PART_NUMBER"SP_CH4221MEE01"
VALUE"DIFF BUS_0.22UF"
$LOCATION"C871"
CDS_LMAN_SYM_OUTLINE"-25,50,25,-50"
CDS_LIB"pure_quanta"
PIN_NAMES_ROTATE"TRUE"
VOLTAGE"6.3V"
MATERIAL"X6S"
PACK_TYPE"C0201"
TOLERANCE"20%"
$LOCATION"C871"
CDS_LOCATION"C871"
$SEC"1"
CDS_SEC"1";
"2"
$PN"2"72;
"1"
$PN"1"35;
%"Q_CAP_DIFFBUS"
"2","(3825,3550)","2","pure_quanta","I169";
;
PART_NUMBER"SP_CH4221MEE01"
MATERIAL"X6S"
VALUE"DIFF BUS_0.22UF"
VOLTAGE"6.3V"
TOLERANCE"20%"
PACK_TYPE"C0201"
$LOCATION"C870"
CDS_LIB"pure_quanta"
CDS_LMAN_SYM_OUTLINE"-25,50,25,-50"
PIN_NAMES_ROTATE"TRUE"
$LOCATION"C870"
CDS_LOCATION"C870"
$SEC"1"
CDS_SEC"1";
"2"
$PN"2"65;
"1"
$PN"1"36;
%"TAP"
"1","(-1625,1525)","2","standard","I17";
;
CDS_LIB"standard"
BODY_TYPE"PLUMBING"
HDL_TAP"TRUE";
"B \NAC \NWC"1;
"S \NAC"
BN"7"137;
%"TAP"
"1","(4375,175)","0","standard","I170";
;
CDS_LIB"standard"
BODY_TYPE"PLUMBING"
HDL_TAP"TRUE";
"B \NAC \NWC"16;
"S \NAC"
BN"0"33;
%"TAP"
"1","(4375,375)","0","standard","I171";
;
CDS_LIB"standard"
BODY_TYPE"PLUMBING"
HDL_TAP"TRUE";
"B \NAC \NWC"16;
"S \NAC"
BN"1"56;
%"TAP"
"1","(4375,575)","0","standard","I172";
;
CDS_LIB"standard"
BODY_TYPE"PLUMBING"
HDL_TAP"TRUE";
"B \NAC \NWC"16;
"S \NAC"
BN"2"55;
%"TAP"
"1","(4375,975)","0","standard","I173";
;
CDS_LIB"standard"
BODY_TYPE"PLUMBING"
HDL_TAP"TRUE";
"B \NAC \NWC"16;
"S \NAC"
BN"4"50;
%"TAP"
"1","(4375,775)","0","standard","I174";
;
CDS_LIB"standard"
BODY_TYPE"PLUMBING"
HDL_TAP"TRUE";
"B \NAC \NWC"16;
"S \NAC"
BN"3"54;
%"TAP"
"1","(4575,125)","0","standard","I175";
;
CDS_LIB"standard"
BODY_TYPE"PLUMBING"
HDL_TAP"TRUE";
"B \NAC \NWC"15;
"S \NAC"
BN"0"32;
%"TAP"
"1","(4575,325)","0","standard","I176";
;
CDS_LIB"standard"
BODY_TYPE"PLUMBING"
HDL_TAP"TRUE";
"B \NAC \NWC"15;
"S \NAC"
BN"1"31;
%"TAP"
"1","(4575,525)","0","standard","I177";
;
CDS_LIB"standard"
BODY_TYPE"PLUMBING"
HDL_TAP"TRUE";
"B \NAC \NWC"15;
"S \NAC"
BN"2"52;
%"TAP"
"1","(4575,725)","0","standard","I178";
;
CDS_LIB"standard"
BODY_TYPE"PLUMBING"
HDL_TAP"TRUE";
"B \NAC \NWC"15;
"S \NAC"
BN"3"51;
%"TAP"
"1","(4575,925)","0","standard","I179";
;
CDS_LIB"standard"
BODY_TYPE"PLUMBING"
HDL_TAP"TRUE";
"B \NAC \NWC"15;
"S \NAC"
BN"4"53;
%"TAP"
"1","(-1375,1175)","2","standard","I18";
;
CDS_LIB"standard"
BODY_TYPE"PLUMBING"
HDL_TAP"TRUE";
"B \NAC \NWC"2;
"S \NAC"
BN"5"133;
%"TAP"
"1","(4375,1175)","0","standard","I180";
;
CDS_LIB"standard"
BODY_TYPE"PLUMBING"
HDL_TAP"TRUE";
"B \NAC \NWC"16;
"S \NAC"
BN"5"49;
%"TAP"
"1","(4375,1375)","0","standard","I181";
;
CDS_LIB"standard"
BODY_TYPE"PLUMBING"
HDL_TAP"TRUE";
"B \NAC \NWC"16;
"S \NAC"
BN"6"48;
%"TAP"
"1","(4375,1575)","0","standard","I182";
;
CDS_LIB"standard"
BODY_TYPE"PLUMBING"
HDL_TAP"TRUE";
"B \NAC \NWC"16;
"S \NAC"
BN"7"47;
%"TAP"
"1","(4575,1125)","0","standard","I183";
;
CDS_LIB"standard"
BODY_TYPE"PLUMBING"
HDL_TAP"TRUE";
"B \NAC \NWC"15;
"S \NAC"
BN"5"59;
%"TAP"
"1","(4575,1325)","0","standard","I184";
;
CDS_LIB"standard"
BODY_TYPE"PLUMBING"
HDL_TAP"TRUE";
"B \NAC \NWC"15;
"S \NAC"
BN"6"58;
%"TAP"
"1","(4575,1525)","0","standard","I185";
;
CDS_LIB"standard"
BODY_TYPE"PLUMBING"
HDL_TAP"TRUE";
"B \NAC \NWC"15;
"S \NAC"
BN"7"46;
%"TAP"
"1","(4375,2150)","0","standard","I188";
;
CDS_LIB"standard"
BODY_TYPE"PLUMBING"
HDL_TAP"TRUE";
"B \NAC \NWC"14;
"S \NAC"
BN"8"44;
%"TAP"
"1","(4375,2350)","0","standard","I189";
;
CDS_LIB"standard"
BODY_TYPE"PLUMBING"
HDL_TAP"TRUE";
"B \NAC \NWC"14;
"S \NAC"
BN"9"45;
%"TAP"
"1","(-1375,1375)","2","standard","I19";
;
CDS_LIB"standard"
BODY_TYPE"PLUMBING"
HDL_TAP"TRUE";
"B \NAC \NWC"2;
"S \NAC"
BN"6"138;
%"TAP"
"1","(4375,2550)","0","standard","I190";
;
CDS_LIB"standard"
BODY_TYPE"PLUMBING"
HDL_TAP"TRUE";
"B \NAC \NWC"14;
"S \NAC"
BN"10"43;
%"TAP"
"1","(4375,2750)","0","standard","I191";
;
CDS_LIB"standard"
BODY_TYPE"PLUMBING"
HDL_TAP"TRUE";
"B \NAC \NWC"14;
"S \NAC"
BN"11"42;
%"TAP"
"1","(4375,2950)","0","standard","I192";
;
CDS_LIB"standard"
BODY_TYPE"PLUMBING"
HDL_TAP"TRUE";
"B \NAC \NWC"14;
"S \NAC"
BN"12"41;
%"TAP"
"1","(4575,2100)","0","standard","I193";
;
CDS_LIB"standard"
BODY_TYPE"PLUMBING"
HDL_TAP"TRUE";
"B \NAC \NWC"13;
"S \NAC"
BN"8"57;
%"TAP"
"1","(4575,2300)","0","standard","I194";
;
CDS_LIB"standard"
BODY_TYPE"PLUMBING"
HDL_TAP"TRUE";
"B \NAC \NWC"13;
"S \NAC"
BN"9"40;
%"TAP"
"1","(4575,2500)","0","standard","I195";
;
CDS_LIB"standard"
BODY_TYPE"PLUMBING"
HDL_TAP"TRUE";
"B \NAC \NWC"13;
"S \NAC"
BN"10"39;
%"TAP"
"1","(4575,2700)","0","standard","I196";
;
CDS_LIB"standard"
BODY_TYPE"PLUMBING"
HDL_TAP"TRUE";
"B \NAC \NWC"13;
"S \NAC"
BN"11"38;
%"TAP"
"1","(4575,2900)","0","standard","I197";
;
CDS_LIB"standard"
BODY_TYPE"PLUMBING"
HDL_TAP"TRUE";
"B \NAC \NWC"13;
"S \NAC"
BN"12"62;
%"TAP"
"1","(4375,3150)","0","standard","I198";
;
CDS_LIB"standard"
BODY_TYPE"PLUMBING"
HDL_TAP"TRUE";
"B \NAC \NWC"14;
"S \NAC"
BN"13"60;
%"TAP"
"1","(4375,3550)","0","standard","I199";
;
CDS_LIB"standard"
BODY_TYPE"PLUMBING"
HDL_TAP"TRUE";
"B \NAC \NWC"14;
"S \NAC"
BN"15"36;
%"TAP"
"1","(-1375,1575)","2","standard","I20";
;
CDS_LIB"standard"
BODY_TYPE"PLUMBING"
HDL_TAP"TRUE";
"B \NAC \NWC"2;
"S \NAC"
BN"7"132;
%"TAP"
"1","(4375,3350)","0","standard","I200";
;
CDS_LIB"standard"
BODY_TYPE"PLUMBING"
HDL_TAP"TRUE";
"B \NAC \NWC"14;
"S \NAC"
BN"14"37;
%"TAP"
"1","(4575,3100)","0","standard","I201";
;
CDS_LIB"standard"
BODY_TYPE"PLUMBING"
HDL_TAP"TRUE";
"B \NAC \NWC"13;
"S \NAC"
BN"13"61;
%"TAP"
"1","(4575,3300)","0","standard","I202";
;
CDS_LIB"standard"
BODY_TYPE"PLUMBING"
HDL_TAP"TRUE";
"B \NAC \NWC"13;
"S \NAC"
BN"14"34;
%"TAP"
"1","(4575,3500)","0","standard","I203";
;
CDS_LIB"standard"
BODY_TYPE"PLUMBING"
HDL_TAP"TRUE";
"B \NAC \NWC"13;
"S \NAC"
BN"15"35;
%"Q_CAP_DIFFBUS"
"2","(3825,375)","2","pure_quanta","I206";
;
PART_NUMBER"SP_CH4221MEE01"
VALUE"DIFF BUS_0.22UF"
$LOCATION"C898"
PIN_NAMES_ROTATE"TRUE"
CDS_LMAN_SYM_OUTLINE"-25,50,25,-50"
CDS_LIB"pure_quanta"
VOLTAGE"6.3V"
MATERIAL"X6S"
PACK_TYPE"C0201"
TOLERANCE"20%"
$LOCATION"C898"
CDS_LOCATION"C898"
$SEC"1"
CDS_SEC"1";
"2"
$PN"2"84;
"1"
$PN"1"56;
%"TAP"
"1","(3100,975)","2","standard","I207";
;
CDS_LIB"standard"
BODY_TYPE"PLUMBING"
HDL_TAP"TRUE";
"B \NAC \NWC"10;
"S \NAC"
BN"4"82;
%"TAP"
"1","(2850,1125)","2","standard","I208";
;
CDS_LIB"standard"
BODY_TYPE"PLUMBING"
HDL_TAP"TRUE";
"B \NAC \NWC"9;
"S \NAC"
BN"5"90;
%"Q_CAP_DIFFBUS"
"2","(-650,125)","2","pure_quanta","I21";
;
PART_NUMBER"SP_CH4221MEE01"
VALUE"DIFF BUS_0.22UF"
$LOCATION"C869"
TOLERANCE"20%"
PACK_TYPE"C0201"
MATERIAL"X6S"
VOLTAGE"6.3V"
CDS_LMAN_SYM_OUTLINE"-25,50,25,-50"
CDS_LIB"pure_quanta"
PIN_NAMES_ROTATE"TRUE"
$LOCATION"C869"
CDS_LOCATION"C869"
$SEC"1"
CDS_SEC"1";
"2"
$PN"2"139;
"1"
$PN"1"25;
%"Q_CAP_DIFFBUS"
"2","(-650,175)","2","pure_quanta","I22";
;
PART_NUMBER"SP_CH4221MEE01"
VALUE"DIFF BUS_0.22UF"
$LOCATION"C868"
TOLERANCE"20%"
PACK_TYPE"C0201"
MATERIAL"X6S"
VOLTAGE"6.3V"
CDS_LMAN_SYM_OUTLINE"-25,50,25,-50"
CDS_LIB"pure_quanta"
PIN_NAMES_ROTATE"TRUE"
$LOCATION"C868"
CDS_LOCATION"C868"
$SEC"1"
CDS_SEC"1";
"2"
$PN"2"136;
"1"
$PN"1"128;
%"Q_CAP_DIFFBUS"
"2","(-650,325)","2","pure_quanta","I23";
;
PART_NUMBER"SP_CH4221MEE01"
VALUE"DIFF BUS_0.22UF"
$LOCATION"C867"
TOLERANCE"20%"
PACK_TYPE"C0201"
MATERIAL"X6S"
VOLTAGE"6.3V"
CDS_LMAN_SYM_OUTLINE"-25,50,25,-50"
CDS_LIB"pure_quanta"
PIN_NAMES_ROTATE"TRUE"
$LOCATION"C867"
CDS_LOCATION"C867"
$SEC"1"
CDS_SEC"1";
"2"
$PN"2"140;
"1"
$PN"1"94;
%"Q_CAP_DIFFBUS"
"2","(-650,375)","2","pure_quanta","I24";
;
PART_NUMBER"SP_CH4221MEE01"
VALUE"DIFF BUS_0.22UF"
$LOCATION"C866"
TOLERANCE"20%"
PACK_TYPE"C0201"
MATERIAL"X6S"
VOLTAGE"6.3V"
CDS_LIB"pure_quanta"
CDS_LMAN_SYM_OUTLINE"-25,50,25,-50"
PIN_NAMES_ROTATE"TRUE"
$LOCATION"C866"
CDS_LOCATION"C866"
$SEC"1"
CDS_SEC"1";
"2"
$PN"2"129;
"1"
$PN"1"127;
%"Q_CAP_DIFFBUS"
"2","(-650,575)","2","pure_quanta","I25";
;
PART_NUMBER"SP_CH4221MEE01"
VALUE"DIFF BUS_0.22UF"
$LOCATION"C864"
TOLERANCE"20%"
PACK_TYPE"C0201"
MATERIAL"X6S"
VOLTAGE"6.3V"
CDS_LMAN_SYM_OUTLINE"-25,50,25,-50"
CDS_LIB"pure_quanta"
PIN_NAMES_ROTATE"TRUE"
$LOCATION"C864"
CDS_LOCATION"C864"
$SEC"1"
CDS_SEC"1";
"2"
$PN"2"142;
"1"
$PN"1"124;
%"Q_CAP_DIFFBUS"
"2","(-650,525)","2","pure_quanta","I26";
;
PART_NUMBER"SP_CH4221MEE01"
VALUE"DIFF BUS_0.22UF"
$LOCATION"C865"
TOLERANCE"20%"
PACK_TYPE"C0201"
MATERIAL"X6S"
VOLTAGE"6.3V"
CDS_LMAN_SYM_OUTLINE"-25,50,25,-50"
CDS_LIB"pure_quanta"
PIN_NAMES_ROTATE"TRUE"
$LOCATION"C865"
CDS_LOCATION"C865"
$SEC"1"
CDS_SEC"1";
"2"
$PN"2"141;
"1"
$PN"1"97;
%"Q_CAP_DIFFBUS"
"2","(-650,725)","2","pure_quanta","I27";
;
PART_NUMBER"SP_CH4221MEE01"
VALUE"DIFF BUS_0.22UF"
$LOCATION"C863"
TOLERANCE"20%"
PACK_TYPE"C0201"
MATERIAL"X6S"
VOLTAGE"6.3V"
CDS_LIB"pure_quanta"
CDS_LMAN_SYM_OUTLINE"-25,50,25,-50"
PIN_NAMES_ROTATE"TRUE"
$LOCATION"C863"
CDS_LOCATION"C863"
$SEC"1"
CDS_SEC"1";
"2"
$PN"2"130;
"1"
$PN"1"96;
%"Q_CAP_DIFFBUS"
"2","(-650,775)","2","pure_quanta","I28";
;
PART_NUMBER"SP_CH4221MEE01"
VALUE"DIFF BUS_0.22UF"
$LOCATION"C862"
TOLERANCE"20%"
PACK_TYPE"C0201"
MATERIAL"X6S"
VOLTAGE"6.3V"
CDS_LIB"pure_quanta"
CDS_LMAN_SYM_OUTLINE"-25,50,25,-50"
PIN_NAMES_ROTATE"TRUE"
$LOCATION"C862"
CDS_LOCATION"C862"
$SEC"1"
CDS_SEC"1";
"2"
$PN"2"135;
"1"
$PN"1"126;
%"Q_CAP_DIFFBUS"
"2","(-650,925)","2","pure_quanta","I29";
;
PART_NUMBER"SP_CH4221MEE01"
VALUE"DIFF BUS_0.22UF"
$LOCATION"C861"
TOLERANCE"20%"
PACK_TYPE"C0201"
MATERIAL"X6S"
VOLTAGE"6.3V"
CDS_LMAN_SYM_OUTLINE"-25,50,25,-50"
CDS_LIB"pure_quanta"
PIN_NAMES_ROTATE"TRUE"
$LOCATION"C861"
CDS_LOCATION"C861"
$SEC"1"
CDS_SEC"1";
"2"
$PN"2"131;
"1"
$PN"1"95;
%"Q_CAP_DIFFBUS"
"2","(-650,975)","2","pure_quanta","I30";
;
PART_NUMBER"SP_CH4221MEE01"
VALUE"DIFF BUS_0.22UF"
$LOCATION"C860"
TOLERANCE"20%"
PACK_TYPE"C0201"
MATERIAL"X6S"
VOLTAGE"6.3V"
CDS_LMAN_SYM_OUTLINE"-25,50,25,-50"
CDS_LIB"pure_quanta"
PIN_NAMES_ROTATE"TRUE"
$LOCATION"C860"
CDS_LOCATION"C860"
$SEC"1"
CDS_SEC"1";
"2"
$PN"2"143;
"1"
$PN"1"125;
%"TAP"
"1","(-100,175)","0","standard","I31";
;
CDS_LIB"standard"
BODY_TYPE"PLUMBING"
HDL_TAP"TRUE";
"B \NAC \NWC"3;
"S \NAC"
BN"0"128;
%"TAP"
"1","(-100,375)","0","standard","I32";
;
CDS_LIB"standard"
BODY_TYPE"PLUMBING"
HDL_TAP"TRUE";
"B \NAC \NWC"3;
"S \NAC"
BN"1"127;
%"TAP"
"1","(-100,575)","0","standard","I33";
;
CDS_LIB"standard"
BODY_TYPE"PLUMBING"
HDL_TAP"TRUE";
"B \NAC \NWC"3;
"S \NAC"
BN"2"124;
%"TAP"
"1","(-100,775)","0","standard","I34";
;
CDS_LIB"standard"
BODY_TYPE"PLUMBING"
HDL_TAP"TRUE";
"B \NAC \NWC"3;
"S \NAC"
BN"3"126;
%"TAP"
"1","(-100,975)","0","standard","I35";
;
CDS_LIB"standard"
BODY_TYPE"PLUMBING"
HDL_TAP"TRUE";
"B \NAC \NWC"3;
"S \NAC"
BN"4"125;
%"Q_CAP_DIFFBUS"
"2","(-650,1125)","2","pure_quanta","I36";
;
PART_NUMBER"SP_CH4221MEE01"
VALUE"DIFF BUS_0.22UF"
$LOCATION"C859"
TOLERANCE"20%"
PACK_TYPE"C0201"
MATERIAL"X6S"
VOLTAGE"6.3V"
CDS_LMAN_SYM_OUTLINE"-25,50,25,-50"
CDS_LIB"pure_quanta"
PIN_NAMES_ROTATE"TRUE"
$LOCATION"C859"
CDS_LOCATION"C859"
$SEC"1"
CDS_SEC"1";
"2"
$PN"2"144;
"1"
$PN"1"92;
%"Q_CAP_DIFFBUS"
"2","(-650,1175)","2","pure_quanta","I37";
;
PART_NUMBER"SP_CH4221MEE01"
VALUE"DIFF BUS_0.22UF"
$LOCATION"C858"
TOLERANCE"20%"
PACK_TYPE"C0201"
MATERIAL"X6S"
VOLTAGE"6.3V"
CDS_LMAN_SYM_OUTLINE"-25,50,25,-50"
CDS_LIB"pure_quanta"
PIN_NAMES_ROTATE"TRUE"
$LOCATION"C858"
CDS_LOCATION"C858"
$SEC"1"
CDS_SEC"1";
"2"
$PN"2"133;
"1"
$PN"1"27;
%"Q_CAP_DIFFBUS"
"2","(-650,1325)","2","pure_quanta","I38";
;
PART_NUMBER"SP_CH4221MEE01"
VALUE"DIFF BUS_0.22UF"
$LOCATION"C857"
TOLERANCE"20%"
PACK_TYPE"C0201"
MATERIAL"X6S"
VOLTAGE"6.3V"
CDS_LMAN_SYM_OUTLINE"-25,50,25,-50"
CDS_LIB"pure_quanta"
PIN_NAMES_ROTATE"TRUE"
$LOCATION"C857"
CDS_LOCATION"C857"
$SEC"1"
CDS_SEC"1";
"2"
$PN"2"134;
"1"
$PN"1"26;
%"Q_CAP_DIFFBUS"
"2","(-650,1375)","2","pure_quanta","I39";
;
PART_NUMBER"SP_CH4221MEE01"
VALUE"DIFF BUS_0.22UF"
$LOCATION"C856"
TOLERANCE"20%"
PACK_TYPE"C0201"
MATERIAL"X6S"
VOLTAGE"6.3V"
CDS_LMAN_SYM_OUTLINE"-25,50,25,-50"
CDS_LIB"pure_quanta"
PIN_NAMES_ROTATE"TRUE"
$LOCATION"C856"
CDS_LOCATION"C856"
$SEC"1"
CDS_SEC"1";
"2"
$PN"2"138;
"1"
$PN"1"123;
%"Q_CAP_DIFFBUS"
"2","(-650,1525)","2","pure_quanta","I40";
;
PART_NUMBER"SP_CH4221MEE01"
VALUE"DIFF BUS_0.22UF"
$LOCATION"C855"
TOLERANCE"20%"
PACK_TYPE"C0201"
MATERIAL"X6S"
VOLTAGE"6.3V"
CDS_LMAN_SYM_OUTLINE"-25,50,25,-50"
CDS_LIB"pure_quanta"
PIN_NAMES_ROTATE"TRUE"
$LOCATION"C855"
CDS_LOCATION"C855"
$SEC"1"
CDS_SEC"1";
"2"
$PN"2"137;
"1"
$PN"1"93;
%"Q_CAP_DIFFBUS"
"2","(-650,1575)","2","pure_quanta","I41";
;
PART_NUMBER"SP_CH4221MEE01"
VALUE"DIFF BUS_0.22UF"
$LOCATION"C854"
TOLERANCE"20%"
PACK_TYPE"C0201"
MATERIAL"X6S"
VOLTAGE"6.3V"
CDS_LIB"pure_quanta"
CDS_LMAN_SYM_OUTLINE"-25,50,25,-50"
PIN_NAMES_ROTATE"TRUE"
$LOCATION"C854"
CDS_LOCATION"C854"
$SEC"1"
CDS_SEC"1";
"2"
$PN"2"132;
"1"
$PN"1"122;
%"TAP"
"1","(-100,1375)","0","standard","I42";
;
CDS_LIB"standard"
BODY_TYPE"PLUMBING"
HDL_TAP"TRUE";
"B \NAC \NWC"3;
"S \NAC"
BN"6"123;
%"TAP"
"1","(-100,1175)","0","standard","I43";
;
CDS_LIB"standard"
BODY_TYPE"PLUMBING"
HDL_TAP"TRUE";
"B \NAC \NWC"3;
"S \NAC"
BN"5"27;
%"TAP"
"1","(-100,1575)","0","standard","I44";
;
CDS_LIB"standard"
BODY_TYPE"PLUMBING"
HDL_TAP"TRUE";
"B \NAC \NWC"3;
"S \NAC"
BN"7"122;
%"TAP"
"1","(-1625,2100)","2","standard","I45";
;
CDS_LIB"standard"
BODY_TYPE"PLUMBING"
HDL_TAP"TRUE";
"B \NAC \NWC"5;
"S \NAC"
BN"8"113;
%"TAP"
"1","(-1625,2300)","2","standard","I46";
;
CDS_LIB"standard"
BODY_TYPE"PLUMBING"
HDL_TAP"TRUE";
"B \NAC \NWC"5;
"S \NAC"
BN"9"112;
%"TAP"
"1","(-1625,2500)","2","standard","I47";
;
CDS_LIB"standard"
BODY_TYPE"PLUMBING"
HDL_TAP"TRUE";
"B \NAC \NWC"5;
"S \NAC"
BN"10"111;
%"TAP"
"1","(-1625,2700)","2","standard","I48";
;
CDS_LIB"standard"
BODY_TYPE"PLUMBING"
HDL_TAP"TRUE";
"B \NAC \NWC"5;
"S \NAC"
BN"11"110;
%"TAP"
"1","(-1625,2900)","2","standard","I49";
;
CDS_LIB"standard"
BODY_TYPE"PLUMBING"
HDL_TAP"TRUE";
"B \NAC \NWC"5;
"S \NAC"
BN"12"24;
%"TAP"
"1","(-1625,125)","2","standard","I5";
;
CDS_LIB"standard"
BODY_TYPE"PLUMBING"
HDL_TAP"TRUE";
"B \NAC \NWC"1;
"S \NAC"
BN"0"139;
%"TAP"
"1","(-1375,2150)","2","standard","I50";
;
CDS_LIB"standard"
BODY_TYPE"PLUMBING"
HDL_TAP"TRUE";
"B \NAC \NWC"4;
"S \NAC"
BN"8"120;
%"TAP"
"1","(-1375,2350)","2","standard","I51";
;
CDS_LIB"standard"
BODY_TYPE"PLUMBING"
HDL_TAP"TRUE";
"B \NAC \NWC"4;
"S \NAC"
BN"9"118;
%"TAP"
"1","(-1375,2550)","2","standard","I52";
;
CDS_LIB"standard"
BODY_TYPE"PLUMBING"
HDL_TAP"TRUE";
"B \NAC \NWC"4;
"S \NAC"
BN"10"119;
%"TAP"
"1","(-1375,2750)","2","standard","I53";
;
CDS_LIB"standard"
BODY_TYPE"PLUMBING"
HDL_TAP"TRUE";
"B \NAC \NWC"4;
"S \NAC"
BN"11"109;
%"TAP"
"1","(-1375,2950)","2","standard","I54";
;
CDS_LIB"standard"
BODY_TYPE"PLUMBING"
HDL_TAP"TRUE";
"B \NAC \NWC"4;
"S \NAC"
BN"12"23;
%"TAP"
"1","(-1625,3500)","2","standard","I55";
;
CDS_LIB"standard"
BODY_TYPE"PLUMBING"
HDL_TAP"TRUE";
"B \NAC \NWC"5;
"S \NAC"
BN"15"116;
%"TAP"
"1","(-1625,3300)","2","standard","I56";
;
CDS_LIB"standard"
BODY_TYPE"PLUMBING"
HDL_TAP"TRUE";
"B \NAC \NWC"5;
"S \NAC"
BN"14"114;
%"TAP"
"1","(-1625,3100)","2","standard","I57";
;
CDS_LIB"standard"
BODY_TYPE"PLUMBING"
HDL_TAP"TRUE";
"B \NAC \NWC"5;
"S \NAC"
BN"13"108;
%"TAP"
"1","(-1375,3150)","2","standard","I58";
;
CDS_LIB"standard"
BODY_TYPE"PLUMBING"
HDL_TAP"TRUE";
"B \NAC \NWC"4;
"S \NAC"
BN"13"117;
%"TAP"
"1","(-1375,3350)","2","standard","I59";
;
CDS_LIB"standard"
BODY_TYPE"PLUMBING"
HDL_TAP"TRUE";
"B \NAC \NWC"4;
"S \NAC"
BN"14"115;
%"TAP"
"1","(-1625,325)","2","standard","I6";
;
CDS_LIB"standard"
BODY_TYPE"PLUMBING"
HDL_TAP"TRUE";
"B \NAC \NWC"1;
"S \NAC"
BN"1"140;
%"TAP"
"1","(-1375,3550)","2","standard","I60";
;
CDS_LIB"standard"
BODY_TYPE"PLUMBING"
HDL_TAP"TRUE";
"B \NAC \NWC"4;
"S \NAC"
BN"15"121;
%"Q_CAP_DIFFBUS"
"2","(-650,2150)","2","pure_quanta","I61";
;
PART_NUMBER"SP_CH4221MEE01"
VALUE"DIFF BUS_0.22UF"
$LOCATION"C852"
TOLERANCE"20%"
PACK_TYPE"C0201"
MATERIAL"X6S"
VOLTAGE"6.3V"
PIN_NAMES_ROTATE"TRUE"
CDS_LIB"pure_quanta"
CDS_LMAN_SYM_OUTLINE"-25,50,25,-50"
$LOCATION"C852"
CDS_LOCATION"C852"
$SEC"1"
CDS_SEC"1";
"2"
$PN"2"120;
"1"
$PN"1"106;
%"Q_CAP_DIFFBUS"
"2","(-650,2100)","2","pure_quanta","I62";
;
PART_NUMBER"SP_CH4221MEE01"
VALUE"DIFF BUS_0.22UF"
$LOCATION"C853"
TOLERANCE"20%"
PACK_TYPE"C0201"
MATERIAL"X6S"
VOLTAGE"6.3V"
PIN_NAMES_ROTATE"TRUE"
CDS_LIB"pure_quanta"
CDS_LMAN_SYM_OUTLINE"-25,50,25,-50"
$LOCATION"C853"
CDS_LOCATION"C853"
$SEC"1"
CDS_SEC"1";
"2"
$PN"2"113;
"1"
$PN"1"98;
%"Q_CAP_DIFFBUS"
"2","(-650,2300)","2","pure_quanta","I63";
;
PART_NUMBER"SP_CH4221MEE01"
VALUE"DIFF BUS_0.22UF"
$LOCATION"C851"
TOLERANCE"20%"
PACK_TYPE"C0201"
MATERIAL"X6S"
VOLTAGE"6.3V"
PIN_NAMES_ROTATE"TRUE"
CDS_LIB"pure_quanta"
CDS_LMAN_SYM_OUTLINE"-25,50,25,-50"
$LOCATION"C851"
CDS_LOCATION"C851"
$SEC"1"
CDS_SEC"1";
"2"
$PN"2"112;
"1"
$PN"1"102;
%"Q_CAP_DIFFBUS"
"2","(-650,2350)","2","pure_quanta","I64";
;
PART_NUMBER"SP_CH4221MEE01"
VALUE"DIFF BUS_0.22UF"
$LOCATION"C850"
TOLERANCE"20%"
PACK_TYPE"C0201"
MATERIAL"X6S"
VOLTAGE"6.3V"
PIN_NAMES_ROTATE"TRUE"
CDS_LMAN_SYM_OUTLINE"-25,50,25,-50"
CDS_LIB"pure_quanta"
$LOCATION"C850"
CDS_LOCATION"C850"
$SEC"1"
CDS_SEC"1";
"2"
$PN"2"118;
"1"
$PN"1"107;
%"Q_CAP_DIFFBUS"
"2","(-650,2500)","2","pure_quanta","I65";
;
PART_NUMBER"SP_CH4221MEE01"
VALUE"DIFF BUS_0.22UF"
$LOCATION"C849"
TOLERANCE"20%"
PACK_TYPE"C0201"
MATERIAL"X6S"
VOLTAGE"6.3V"
PIN_NAMES_ROTATE"TRUE"
CDS_LIB"pure_quanta"
CDS_LMAN_SYM_OUTLINE"-25,50,25,-50"
$LOCATION"C849"
CDS_LOCATION"C849"
$SEC"1"
CDS_SEC"1";
"2"
$PN"2"111;
"1"
$PN"1"101;
%"Q_CAP_DIFFBUS"
"2","(-650,2550)","2","pure_quanta","I66";
;
PART_NUMBER"SP_CH4221MEE01"
VALUE"DIFF BUS_0.22UF"
$LOCATION"C848"
TOLERANCE"20%"
PACK_TYPE"C0201"
MATERIAL"X6S"
VOLTAGE"6.3V"
PIN_NAMES_ROTATE"TRUE"
CDS_LIB"pure_quanta"
CDS_LMAN_SYM_OUTLINE"-25,50,25,-50"
$LOCATION"C848"
CDS_LOCATION"C848"
$SEC"1"
CDS_SEC"1";
"2"
$PN"2"119;
"1"
$PN"1"105;
%"Q_CAP_DIFFBUS"
"2","(-650,2700)","2","pure_quanta","I67";
;
PART_NUMBER"SP_CH4221MEE01"
VALUE"DIFF BUS_0.22UF"
$LOCATION"C847"
TOLERANCE"20%"
PACK_TYPE"C0201"
MATERIAL"X6S"
VOLTAGE"6.3V"
PIN_NAMES_ROTATE"TRUE"
CDS_LMAN_SYM_OUTLINE"-25,50,25,-50"
CDS_LIB"pure_quanta"
$LOCATION"C847"
CDS_LOCATION"C847"
$SEC"1"
CDS_SEC"1";
"2"
$PN"2"110;
"1"
$PN"1"100;
%"Q_CAP_DIFFBUS"
"2","(-650,2750)","2","pure_quanta","I68";
;
PART_NUMBER"SP_CH4221MEE01"
VALUE"DIFF BUS_0.22UF"
$LOCATION"C846"
TOLERANCE"20%"
PACK_TYPE"C0201"
MATERIAL"X6S"
VOLTAGE"6.3V"
PIN_NAMES_ROTATE"TRUE"
CDS_LMAN_SYM_OUTLINE"-25,50,25,-50"
CDS_LIB"pure_quanta"
$LOCATION"C846"
CDS_LOCATION"C846"
$SEC"1"
CDS_SEC"1";
"2"
$PN"2"109;
"1"
$PN"1"104;
%"Q_CAP_DIFFBUS"
"2","(-650,2900)","2","pure_quanta","I69";
;
PART_NUMBER"SP_CH4221MEE01"
VALUE"DIFF BUS_0.22UF"
$LOCATION"C845"
TOLERANCE"20%"
PACK_TYPE"C0201"
MATERIAL"X6S"
VOLTAGE"6.3V"
PIN_NAMES_ROTATE"TRUE"
CDS_LIB"pure_quanta"
CDS_LMAN_SYM_OUTLINE"-25,50,25,-50"
$LOCATION"C845"
CDS_LOCATION"C845"
$SEC"1"
CDS_SEC"1";
"2"
$PN"2"24;
"1"
$PN"1"99;
%"TAP"
"1","(-1625,525)","2","standard","I7";
;
CDS_LIB"standard"
BODY_TYPE"PLUMBING"
HDL_TAP"TRUE";
"B \NAC \NWC"1;
"S \NAC"
BN"2"141;
%"Q_CAP_DIFFBUS"
"2","(-650,2950)","2","pure_quanta","I70";
;
PART_NUMBER"SP_CH4221MEE01"
VALUE"DIFF BUS_0.22UF"
$LOCATION"C844"
TOLERANCE"20%"
PACK_TYPE"C0201"
MATERIAL"X6S"
VOLTAGE"6.3V"
PIN_NAMES_ROTATE"TRUE"
CDS_LIB"pure_quanta"
CDS_LMAN_SYM_OUTLINE"-25,50,25,-50"
$LOCATION"C844"
CDS_LOCATION"C844"
$SEC"1"
CDS_SEC"1";
"2"
$PN"2"23;
"1"
$PN"1"103;
%"TAP"
"1","(-100,2150)","0","standard","I71";
;
CDS_LIB"standard"
BODY_TYPE"PLUMBING"
HDL_TAP"TRUE";
"B \NAC \NWC"6;
"S \NAC"
BN"8"106;
%"TAP"
"1","(-100,2350)","0","standard","I72";
;
CDS_LIB"standard"
BODY_TYPE"PLUMBING"
HDL_TAP"TRUE";
"B \NAC \NWC"6;
"S \NAC"
BN"9"107;
%"TAP"
"1","(-100,2550)","0","standard","I73";
;
CDS_LIB"standard"
BODY_TYPE"PLUMBING"
HDL_TAP"TRUE";
"B \NAC \NWC"6;
"S \NAC"
BN"10"105;
%"TAP"
"1","(-100,2750)","0","standard","I74";
;
CDS_LIB"standard"
BODY_TYPE"PLUMBING"
HDL_TAP"TRUE";
"B \NAC \NWC"6;
"S \NAC"
BN"11"104;
%"TAP"
"1","(-100,2950)","0","standard","I75";
;
CDS_LIB"standard"
BODY_TYPE"PLUMBING"
HDL_TAP"TRUE";
"B \NAC \NWC"6;
"S \NAC"
BN"12"103;
%"Q_CAP_DIFFBUS"
"2","(-650,3150)","2","pure_quanta","I76";
;
PART_NUMBER"SP_CH4221MEE01"
VALUE"DIFF BUS_0.22UF"
$LOCATION"C842"
TOLERANCE"20%"
PACK_TYPE"C0201"
MATERIAL"X6S"
VOLTAGE"6.3V"
PIN_NAMES_ROTATE"TRUE"
CDS_LIB"pure_quanta"
CDS_LMAN_SYM_OUTLINE"-25,50,25,-50"
$LOCATION"C842"
CDS_LOCATION"C842"
$SEC"1"
CDS_SEC"1";
"2"
$PN"2"117;
"1"
$PN"1"21;
%"Q_CAP_DIFFBUS"
"2","(-650,3100)","2","pure_quanta","I77";
;
PART_NUMBER"SP_CH4221MEE01"
VALUE"DIFF BUS_0.22UF"
$LOCATION"C843"
TOLERANCE"20%"
PACK_TYPE"C0201"
MATERIAL"X6S"
VOLTAGE"6.3V"
PIN_NAMES_ROTATE"TRUE"
CDS_LIB"pure_quanta"
CDS_LMAN_SYM_OUTLINE"-25,50,25,-50"
$LOCATION"C843"
CDS_LOCATION"C843"
$SEC"1"
CDS_SEC"1";
"2"
$PN"2"108;
"1"
$PN"1"22;
%"Q_CAP_DIFFBUS"
"2","(-650,3300)","2","pure_quanta","I78";
;
PART_NUMBER"SP_CH4221MEE01"
VALUE"DIFF BUS_0.22UF"
$LOCATION"C841"
TOLERANCE"20%"
PACK_TYPE"C0201"
MATERIAL"X6S"
VOLTAGE"6.3V"
PIN_NAMES_ROTATE"TRUE"
CDS_LIB"pure_quanta"
CDS_LMAN_SYM_OUTLINE"-25,50,25,-50"
$LOCATION"C841"
CDS_LOCATION"C841"
$SEC"1"
CDS_SEC"1";
"2"
$PN"2"114;
"1"
$PN"1"20;
%"Q_CAP_DIFFBUS"
"2","(-650,3350)","2","pure_quanta","I79";
;
PART_NUMBER"SP_CH4221MEE01"
VALUE"DIFF BUS_0.22UF"
$LOCATION"C840"
TOLERANCE"20%"
PACK_TYPE"C0201"
MATERIAL"X6S"
VOLTAGE"6.3V"
PIN_NAMES_ROTATE"TRUE"
CDS_LIB"pure_quanta"
CDS_LMAN_SYM_OUTLINE"-25,50,25,-50"
$LOCATION"C840"
CDS_LOCATION"C840"
$SEC"1"
CDS_SEC"1";
"2"
$PN"2"115;
"1"
$PN"1"19;
%"TAP"
"1","(-1625,725)","2","standard","I8";
;
CDS_LIB"standard"
BODY_TYPE"PLUMBING"
HDL_TAP"TRUE";
"B \NAC \NWC"1;
"S \NAC"
BN"3"130;
%"Q_CAP_DIFFBUS"
"2","(-650,3550)","2","pure_quanta","I80";
;
PART_NUMBER"SP_CH4221MEE01"
VALUE"DIFF BUS_0.22UF"
PACK_TYPE"C0201"
TOLERANCE"20%"
MATERIAL"X6S"
VOLTAGE"6.3V"
$LOCATION"C838"
PIN_NAMES_ROTATE"TRUE"
CDS_LMAN_SYM_OUTLINE"-25,50,25,-50"
CDS_LIB"pure_quanta"
$LOCATION"C838"
CDS_LOCATION"C838"
$SEC"1"
CDS_SEC"1";
"2"
$PN"2"121;
"1"
$PN"1"17;
%"Q_CAP_DIFFBUS"
"2","(-650,3500)","2","pure_quanta","I81";
;
PART_NUMBER"SP_CH4221MEE01"
VALUE"DIFF BUS_0.22UF"
$LOCATION"C839"
TOLERANCE"20%"
PACK_TYPE"C0201"
MATERIAL"X6S"
VOLTAGE"6.3V"
PIN_NAMES_ROTATE"TRUE"
CDS_LIB"pure_quanta"
CDS_LMAN_SYM_OUTLINE"-25,50,25,-50"
$LOCATION"C839"
CDS_LOCATION"C839"
$SEC"1"
CDS_SEC"1";
"2"
$PN"2"116;
"1"
$PN"1"18;
%"TAP"
"1","(-100,3550)","0","standard","I82";
;
CDS_LIB"standard"
BODY_TYPE"PLUMBING"
HDL_TAP"TRUE";
"B \NAC \NWC"6;
"S \NAC"
BN"15"17;
%"TAP"
"1","(-100,3350)","0","standard","I83";
;
CDS_LIB"standard"
BODY_TYPE"PLUMBING"
HDL_TAP"TRUE";
"B \NAC \NWC"6;
"S \NAC"
BN"14"19;
%"TAP"
"1","(-100,3150)","0","standard","I84";
;
CDS_LIB"standard"
BODY_TYPE"PLUMBING"
HDL_TAP"TRUE";
"B \NAC \NWC"6;
"S \NAC"
BN"13"21;
%"TAP"
"1","(100,125)","0","standard","I85";
;
CDS_LIB"standard"
BODY_TYPE"PLUMBING"
HDL_TAP"TRUE";
"B \NAC \NWC"8;
"S \NAC"
BN"0"25;
%"TAP"
"1","(100,325)","0","standard","I86";
;
CDS_LIB"standard"
BODY_TYPE"PLUMBING"
HDL_TAP"TRUE";
"B \NAC \NWC"8;
"S \NAC"
BN"1"94;
%"TAP"
"1","(100,525)","0","standard","I87";
;
CDS_LIB"standard"
BODY_TYPE"PLUMBING"
HDL_TAP"TRUE";
"B \NAC \NWC"8;
"S \NAC"
BN"2"97;
%"TAP"
"1","(100,725)","0","standard","I88";
;
CDS_LIB"standard"
BODY_TYPE"PLUMBING"
HDL_TAP"TRUE";
"B \NAC \NWC"8;
"S \NAC"
BN"3"96;
%"TAP"
"1","(100,925)","0","standard","I89";
;
CDS_LIB"standard"
BODY_TYPE"PLUMBING"
HDL_TAP"TRUE";
"B \NAC \NWC"8;
"S \NAC"
BN"4"95;
%"TAP"
"1","(-1625,925)","2","standard","I9";
;
CDS_LIB"standard"
BODY_TYPE"PLUMBING"
HDL_TAP"TRUE";
"B \NAC \NWC"1;
"S \NAC"
BN"4"131;
%"TAP"
"1","(100,1125)","0","standard","I90";
;
CDS_LIB"standard"
BODY_TYPE"PLUMBING"
HDL_TAP"TRUE";
"B \NAC \NWC"8;
"S \NAC"
BN"5"92;
%"TAP"
"1","(100,1325)","0","standard","I91";
;
CDS_LIB"standard"
BODY_TYPE"PLUMBING"
HDL_TAP"TRUE";
"B \NAC \NWC"8;
"S \NAC"
BN"6"26;
%"TAP"
"1","(100,1525)","0","standard","I92";
;
CDS_LIB"standard"
BODY_TYPE"PLUMBING"
HDL_TAP"TRUE";
"B \NAC \NWC"8;
"S \NAC"
BN"7"93;
%"TAP"
"1","(100,2100)","0","standard","I97";
;
CDS_LIB"standard"
BODY_TYPE"PLUMBING"
HDL_TAP"TRUE";
"B \NAC \NWC"7;
"S \NAC"
BN"8"98;
%"TAP"
"1","(100,2300)","0","standard","I98";
;
CDS_LIB"standard"
BODY_TYPE"PLUMBING"
HDL_TAP"TRUE";
"B \NAC \NWC"7;
"S \NAC"
BN"9"102;
%"TAP"
"1","(100,2500)","0","standard","I99";
;
CDS_LIB"standard"
BODY_TYPE"PLUMBING"
HDL_TAP"TRUE";
"B \NAC \NWC"7;
"S \NAC"
BN"10"101;
END.
